FILE_TYPE = MACRO_DRAWING;
SET COLOR_WIRE YELLOW;
SET COLOR_PROP MONO;
SET COLOR_DOT WHITE;
SET COLOR_ARC YELLOW;
SET COLOR_BODY GREEN;
SET COLOR_NOTE MONO;
SET PROP_DISPLAY VALUE;
SET PAGE_NUMBER P19;
FORCEADD INTEL_CORP_BPAGE..1
(0 0);
FORCEPROP 1 LAST CDS_CON_LAST_MODIFIED Fri Jun 16 17:48:05 2017
J 0
(-1425 325);
PAINT ORANGE (-1425 325);
DISPLAY INVISIBLE (-1425 325);
FORCEPROP 1 LAST CUSTOM_TXT_CDS <CURRENT_DESIGN_SHEET> OF <TOTAL_DESIGN_SHEETS>
J 0
(-500 25);
PAINT ORANGE (-500 25);
FORCEPROP 1 LAST CUSTOM_TXT_CDS <CON_LAST_MODIFIED>
J 0
(-4000 100);
PAINT ORANGE (-4000 100);
FORCEPROP 2 LAST CUSTOM_TXT_CDS <XR_PAGE_TITLE>
J 0
(-7890 5250);
DISPLAY 0.638298 (-7890 5250);
PAINT PINK (-7890 5250);
DISPLAY INVISIBLE (-7890 5250);
FORCEPROP 1 LAST SCH_TITLE PCIE-LANE REVERSAL & POLARITY INV
J 0
(-7950 50);
DISPLAY 1.212766 (-7950 50);
PAINT ORANGE (-7950 50);
FORCEPROP 2 LAST PAGE_BORDER TRUE
J 0
(-7890 5250);
DISPLAY 0.638298 (-7890 5250);
PAINT PINK (-7890 5250);
DISPLAY INVISIBLE (-7890 5250);
FORCEPROP 2 LAST CDS_LIB mstr_symbols
J 0
(0 0);
PAINT MONO (0 0);
DISPLAY INVISIBLE (0 0);
FORCEPROP 1 LAST COMMENT_BODY TRUE
J 0
(12 12);
DISPLAY 0.468085 (12 12);
PAINT GREEN (12 12);
DISPLAY INVISIBLE (12 12);
FORCEPROP 2 LAST CDS_XR_PAGE_TITLE CR-19 : @BASEBOARD_FAB2_LIB.BASEBOARD_FAB2(SCH_1):PAGE19
J 0
(-7890 5250);
DISPLAY 0.638298 (-7890 5250);
PAINT PINK (-7890 5250);
DISPLAY INVISIBLE (-7890 5250);
FORCENOTE
$CDS_IMAGE|Tioga Pass PCIe topology_3_0317.jpg|4250|3187
(-5800 3275) 0;
DISPLAY LEFT (-5800 3275);
FORCENOTE
$CDS_IMAGE|019_PCIe.jpg|3250|3263
(-1975 3300) 0;
DISPLAY LEFT (-1975 3300);
FORCENOTE
$CDS_IMAGE|clipboard_0.jpg|3625|1125
(-1967 1006) 0;
DISPLAY LEFT (-1967 1006);
QUIT
